# TIMECARD (Time Appliance Project (Time Card)) — schematic netlist excerpt (pin names and nets, part order shuffled) for the footprints in the layout excerpt that follows; sources: Cadence DE-HDL packaged netlist, KiCad conversion of R4006-B0001-02_R01.brd

R10  RESISTOR  10KOHM 1%  pkg SMC_0402R_H016  page 27 : \1\ = XP12R0V_A_IMON ; \2\ = SG
C216  CAPACITOR  0.1UF 10V 10%  pkg SMC_0402R_H022  page 14 : \1\ = XP3R3V_FPGA ; \2\ = SG

(kicad_pcb
	(version 20260206)
	(generator "pcbnew")
	(generator_version "10.0")
	(general
		(thickness 1.6)
		(legacy_teardrops no)
	)
	(paper "A4")
	(title_block
		(title "timecard-production-celestica-r4006 — R4006-B0001-02_R01.brd")
		(comment 1 "Time Appliance Project (Time Card) / footprints 1059-1060 of 1113")
	)
	(layers
		(0 "F.Cu" signal "TOP")
		(4 "In1.Cu" signal "L02_GND1")
		(6 "In2.Cu" signal "L03_SIG1")
		(8 "In3.Cu" signal "L04_GND2")
		(10 "In4.Cu" signal "L05_VCC1")
		(12 "In5.Cu" signal "L06_VCC2")
		(14 "In6.Cu" signal "L07_GND3")
		(16 "In7.Cu" signal "L08_SIG2")
		(18 "In8.Cu" signal "L09_GND4")
		(2 "B.Cu" signal "BOTTOM")
		(9 "F.Adhes" user "F.Adhesive")
		(11 "B.Adhes" user "B.Adhesive")
		(13 "F.Paste" user "Package Geometry/Pastemask Top")
		(15 "B.Paste" user "Package Geometry/Pastemask Bottom")
		(5 "F.SilkS" user "Ref Des/Silkscreen Top")
		(7 "B.SilkS" user "Ref Des/Silkscreen Bottom")
		(1 "F.Mask" user "Board Geometry/Soldermask Top")
		(3 "B.Mask" user "Board Geometry/Soldermask Bottom")
		(17 "Dwgs.User" user "User.Drawings")
		(19 "Cmts.User" user "User.Comments")
		(21 "Eco1.User" user "User.Eco1")
		(23 "Eco2.User" user "User.Eco2")
		(25 "Edge.Cuts" user "Board Geometry/Outline")
		(27 "Margin" user)
		(31 "F.CrtYd" user "Package Geometry/Place Bound Top")
		(29 "B.CrtYd" user "Package Geometry/Place Bound Bottom")
		(35 "F.Fab" user "Ref Des/Assembly Top")
		(33 "B.Fab" user "Ref Des/Assembly Bottom")
	)
	(footprint ""
		(layer "B.Cu")
		(at 145.8214 -97.9678 180)
		(property "Reference" "R10"
			(at -3.1496 0.03683 0)
			(unlocked yes)
			(layer "B.SilkS")
			(effects
				(font
					(size 0.7874 0.5842)
					(thickness 0.1524)
				)
				(justify mirror)
			)
		)
		(property "Value" "VAL*"
			(at -0.02032 2.13233 180)
			(unlocked yes)
			(layer "B.Fab")
			(hide yes)
			(effects
				(font
					(size 0.7874 0.5842)
					(thickness 0.1524)
				)
				(justify mirror)
			)
		)
		(property "Device Type" "RESISTOR-G155-11002-01,10KOHM,A"
			(at -0.008382 1.210564 180)
			(unlocked yes)
			(layer "B.Fab")
			(hide yes)
			(effects
				(font
					(size 0.7874 0.5842)
					(thickness 0.1524)
				)
				(justify mirror)
			)
		)
		(property "User Part Number" "PARTNUM*"
			(at -0.02032 4.024884 180)
			(unlocked yes)
			(layer "Cmts.User")
			(hide yes)
			(effects
				(font
					(size 0.7874 0.5842)
					(thickness 0.1524)
				)
				(justify mirror)
			)
		)
		(property "Tolerance" "TOL*"
			(at -0.044704 3.05435 180)
			(unlocked yes)
			(layer "Cmts.User")
			(hide yes)
			(effects
				(font
					(size 0.7874 0.5842)
					(thickness 0.1524)
				)
				(justify mirror)
			)
		)
		(duplicate_pad_numbers_are_jumpers no)
		(fp_line
			(start 1.143 0.5588)
			(end -1.143 0.5588)
			(stroke
				(width 0.1)
				(type default)
			)
			(layer "B.SilkS")
		)
		(fp_line
			(start 1.143 -0.5588)
			(end 1.143 0.5588)
			(stroke
				(width 0.1)
				(type default)
			)
			(layer "B.SilkS")
		)
		(fp_line
			(start -1.143 0.5588)
			(end -1.143 -0.5588)
			(stroke
				(width 0.1)
				(type default)
			)
			(layer "B.SilkS")
		)
		(fp_line
			(start -1.143 -0.5588)
			(end 1.143 -0.5588)
			(stroke
				(width 0.1)
				(type default)
			)
			(layer "B.SilkS")
		)
		(fp_rect
			(start 1.143 -0.5588)
			(end -1.143 0.5588)
			(stroke
				(width 0)
				(type default)
			)
			(fill no)
			(layer "B.CrtYd")
		)
		(fp_line
			(start 0.508 0.3048)
			(end -0.508 0.3048)
			(stroke
				(width 0.1)
				(type default)
			)
			(layer "B.Fab")
		)
		(fp_line
			(start 0.508 -0.3048)
			(end 0.508 0.3048)
			(stroke
				(width 0.1)
				(type default)
			)
			(layer "B.Fab")
		)
		(fp_line
			(start -0.508 0.3048)
			(end -0.508 -0.3048)
			(stroke
				(width 0.1)
				(type default)
			)
			(layer "B.Fab")
		)
		(fp_line
			(start -0.508 -0.3048)
			(end 0.508 -0.3048)
			(stroke
				(width 0.1)
				(type default)
			)
			(layer "B.Fab")
		)
		(pad "1" smd rect
			(at 0.5334 0)
			(size 0.7112 0.6096)
			(layers "B.Cu" "B.Mask" "B.Paste")
			(net "XP12R0V_A_IMON")
		)
		(pad "2" smd rect
			(at -0.5334 0)
			(size 0.7112 0.6096)
			(layers "B.Cu" "B.Mask" "B.Paste")
			(net "SG")
		)
		(zone
			(layer "B.Cu")
			(hatch none 0.5)
			(connect_pads
				(clearance 0)
			)
			(min_thickness 0.25)
			(keepout
				(tracks allowed)
				(vias not_allowed)
				(pads allowed)
				(copperpour not_allowed)
				(footprints allowed)
			)
			(placement
				(enabled no)
				(sheetname "")
			)
			(fill
				(thermal_gap 0.5)
				(thermal_bridge_width 0.5)
				(island_removal_mode 0)
			)
			(polygon
				(pts
					(xy 145.7452 -97.663) (xy 145.8976 -97.663) (xy 145.8976 -98.2726) (xy 145.7452 -98.2726)
				)
			)
		)
	)
	(footprint ""
		(layer "B.Cu")
		(at 99.346766 -54.823106)
		(property "Reference" "C216"
			(at -1.556766 -1.271524 0)
			(unlocked yes)
			(layer "B.SilkS")
			(effects
				(font
					(size 0.7874 0.5842)
					(thickness 0.1524)
				)
				(justify mirror)
			)
		)
		(property "Value" "VAL*"
			(at 0 3.718306 0)
			(unlocked yes)
			(layer "B.Fab")
			(hide yes)
			(effects
				(font
					(size 0.7874 0.5842)
					(thickness 0.127)
				)
				(justify mirror)
			)
		)
		(property "Tolerance" "TOL*"
			(at 0 4.861306 0)
			(unlocked yes)
			(layer "Cmts.User")
			(hide yes)
			(effects
				(font
					(size 0.7874 0.5842)
					(thickness 0.127)
				)
				(justify mirror)
			)
		)
		(property "User Part Number" "PARTNUM*"
			(at 0 2.575306 0)
			(unlocked yes)
			(layer "Cmts.User")
			(hide yes)
			(effects
				(font
					(size 0.7874 0.5842)
					(thickness 0.127)
				)
				(justify mirror)
			)
		)
		(property "Device Type" "CAPACITOR-G105-0B104-CK,0.1UF,A"
			(at 0 1.432306 0)
			(unlocked yes)
			(layer "B.Fab")
			(hide yes)
			(effects
				(font
					(size 0.7874 0.5842)
					(thickness 0.127)
				)
				(justify mirror)
			)
		)
		(duplicate_pad_numbers_are_jumpers no)
		(fp_line
			(start -0.970026 -0.4699)
			(end -0.970026 0.4699)
			(stroke
				(width 0.1)
				(type default)
			)
			(layer "B.SilkS")
		)
		(fp_line
			(start -0.970026 0.4699)
			(end 0.970026 0.4699)
			(stroke
				(width 0.1)
				(type default)
			)
			(layer "B.SilkS")
		)
		(fp_line
			(start 0.970026 -0.4699)
			(end -0.970026 -0.4699)
			(stroke
				(width 0.1)
				(type default)
			)
			(layer "B.SilkS")
		)
		(fp_line
			(start 0.970026 0.4699)
			(end 0.970026 -0.4699)
			(stroke
				(width 0.1)
				(type default)
			)
			(layer "B.SilkS")
		)
		(fp_poly
			(pts
				(xy 0.970026 0.4699) (xy -0.970026 0.4699) (xy -0.970026 -0.4699) (xy 0.970026 -0.4699)
			)
			(stroke
				(width 0)
				(type default)
			)
			(fill no)
			(layer "B.CrtYd")
		)
		(fp_line
			(start -0.508 -0.3048)
			(end -0.508 0.3048)
			(stroke
				(width 0.1)
				(type default)
			)
			(layer "B.Fab")
		)
		(fp_line
			(start -0.508 0.3048)
			(end 0.508 0.3048)
			(stroke
				(width 0.1)
				(type default)
			)
			(layer "B.Fab")
		)
		(fp_line
			(start 0.508 -0.3048)
			(end -0.508 -0.3048)
			(stroke
				(width 0.1)
				(type default)
			)
			(layer "B.Fab")
		)
		(fp_line
			(start 0.508 0.3048)
			(end 0.508 -0.3048)
			(stroke
				(width 0.1)
				(type default)
			)
			(layer "B.Fab")
		)
		(pad "1" smd circle
			(at 0.500126 0 180)
			(size 0.635 0.635)
			(layers "B.Cu" "B.Mask" "B.Paste")
			(net "XP3R3V_FPGA")
		)
		(pad "2" smd circle
			(at -0.500126 0 180)
			(size 0.635 0.635)
			(layers "B.Cu" "B.Mask" "B.Paste")
			(net "SG")
		)
	)
)
